# S9S_MB_2U (Grand Teton) — schematic netlist excerpt (pin names and nets, part order shuffled) for the footprints in the layout excerpt that follows; sources: Cadence DE-HDL packaged netlist, KiCad conversion of 03242023_DA0F0TMBIJ0_F0T_Motherboard_J_brd_V01_OCP.brd

R3571  Q_RES  10 1% CHIP  pkg 0402LF  page 172 : A = P3V3_OCP_V3_2 ; B = VSENSE_P12V_INA230_3_INN
R2373  Q_RES  1K 1% CHIP  pkg 0402LF  page 266 : A = P3V3_AUX ; B = IRQ_PVCCIN_CPU0_VRHOT_R_N

(kicad_pcb
	(version 20260206)
	(generator "pcbnew")
	(generator_version "10.0")
	(general
		(thickness 1.6)
		(legacy_teardrops no)
	)
	(paper "A4")
	(title_block
		(title "03242023_DA0F0TMBIJ0_F0T_Motherboard_J_brd_V01_OCP.brd")
		(comment 1 "Grand Teton / footprints 6060-6061 of 6105")
	)
	(layers
		(0 "F.Cu" signal "TOP")
		(4 "In1.Cu" signal "GND")
		(6 "In2.Cu" signal "IN1")
		(8 "In3.Cu" signal "GND1")
		(10 "In4.Cu" signal "IN2")
		(12 "In5.Cu" signal "GND2")
		(14 "In6.Cu" signal "IN3")
		(16 "In7.Cu" signal "GND3")
		(18 "In8.Cu" signal "VCC")
		(20 "In9.Cu" signal "VCC1")
		(22 "In10.Cu" signal "GND4")
		(24 "In11.Cu" signal "IN4")
		(26 "In12.Cu" signal "GND5")
		(28 "In13.Cu" signal "IN5")
		(30 "In14.Cu" signal "GND6")
		(32 "In15.Cu" signal "IN6")
		(34 "In16.Cu" signal "GND7")
		(2 "B.Cu" signal "BOTTOM")
		(9 "F.Adhes" user "F.Adhesive")
		(11 "B.Adhes" user "B.Adhesive")
		(13 "F.Paste" user "Package Geometry/Pastemask Top")
		(15 "B.Paste" user "Package Geometry/Pastemask Bottom")
		(5 "F.SilkS" user "Ref Des/Silkscreen Top")
		(7 "B.SilkS" user "Ref Des/Silkscreen Bottom")
		(1 "F.Mask" user "Board Geometry/Soldermask Top")
		(3 "B.Mask" user "Board Geometry/Soldermask Bottom")
		(17 "Dwgs.User" user "User.Drawings")
		(19 "Cmts.User" user "User.Comments")
		(21 "Eco1.User" user "User.Eco1")
		(23 "Eco2.User" user "User.Eco2")
		(25 "Edge.Cuts" user "Board Geometry/Outline")
		(27 "Margin" user)
		(31 "F.CrtYd" user "Package Geometry/Place Bound Top")
		(29 "B.CrtYd" user "Package Geometry/Place Bound Bottom")
		(35 "F.Fab" user "Ref Des/Assembly Top")
		(33 "B.Fab" user "Ref Des/Assembly Bottom")
	)
	(footprint ""
		(layer "B.Cu")
		(at 351.26803 -359.103168 180)
		(property "Reference" "R2373"
			(at 0 0 0)
			(layer "B.SilkS")
			(hide yes)
			(effects
				(font
					(size 1.27 1.27)
				)
				(justify mirror)
			)
		)
		(property "Value" ""
			(at 0 0 0)
			(layer "B.Fab")
			(effects
				(font
					(size 1.27 1.27)
				)
				(justify mirror)
			)
		)
		(duplicate_pad_numbers_are_jumpers no)
		(fp_line
			(start 0.7874 0.4064)
			(end 0.7874 -0.4064)
			(stroke
				(width 0.1524)
				(type default)
			)
			(layer "B.SilkS")
		)
		(fp_line
			(start 0.7874 -0.4064)
			(end -0.7874 -0.4064)
			(stroke
				(width 0.1524)
				(type default)
			)
			(layer "B.SilkS")
		)
		(fp_line
			(start -0.7874 0.4064)
			(end 0.7874 0.4064)
			(stroke
				(width 0.1524)
				(type default)
			)
			(layer "B.SilkS")
		)
		(fp_line
			(start -0.7874 -0.4064)
			(end -0.7874 0.4064)
			(stroke
				(width 0.1524)
				(type default)
			)
			(layer "B.SilkS")
		)
		(fp_line
			(start 0.67945 0.3048)
			(end 0.67945 -0.305054)
			(stroke
				(width 0.1)
				(type default)
			)
			(layer "B.Fab")
		)
		(fp_line
			(start 0.67945 -0.305054)
			(end 0.12065 -0.305054)
			(stroke
				(width 0.1)
				(type default)
			)
			(layer "B.Fab")
		)
		(fp_line
			(start 0.12065 0.3048)
			(end 0.67945 0.3048)
			(stroke
				(width 0.1)
				(type default)
			)
			(layer "B.Fab")
		)
		(fp_line
			(start 0.12065 0.2794)
			(end 0.12065 0.3048)
			(stroke
				(width 0.1)
				(type default)
			)
			(layer "B.Fab")
		)
		(fp_line
			(start 0.12065 -0.2794)
			(end -0.12065 -0.2794)
			(stroke
				(width 0.1)
				(type default)
			)
			(layer "B.Fab")
		)
		(fp_line
			(start 0.12065 -0.305054)
			(end 0.12065 -0.2794)
			(stroke
				(width 0.1)
				(type default)
			)
			(layer "B.Fab")
		)
		(fp_line
			(start -0.120396 0.3048)
			(end -0.120396 0.2794)
			(stroke
				(width 0.1)
				(type default)
			)
			(layer "B.Fab")
		)
		(fp_line
			(start -0.120396 0.2794)
			(end 0.12065 0.2794)
			(stroke
				(width 0.1)
				(type default)
			)
			(layer "B.Fab")
		)
		(fp_line
			(start -0.12065 -0.2794)
			(end -0.12065 -0.3048)
			(stroke
				(width 0.1)
				(type default)
			)
			(layer "B.Fab")
		)
		(fp_line
			(start -0.12065 -0.3048)
			(end -0.67945 -0.3048)
			(stroke
				(width 0.1)
				(type default)
			)
			(layer "B.Fab")
		)
		(fp_line
			(start -0.67945 0.3048)
			(end -0.120396 0.3048)
			(stroke
				(width 0.1)
				(type default)
			)
			(layer "B.Fab")
		)
		(fp_line
			(start -0.67945 -0.3048)
			(end -0.67945 0.3048)
			(stroke
				(width 0.1)
				(type default)
			)
			(layer "B.Fab")
		)
		(pad "1" smd circle
			(at 0.40005 0)
			(size 0 0)
			(layers "B.Cu" "B.Mask" "B.Paste")
			(net "P3V3_AUX")
		)
		(pad "2" smd circle
			(at -0.40005 0)
			(size 0 0)
			(layers "B.Cu" "B.Mask" "B.Paste")
			(net "IRQ_PVCCIN_CPU0_VRHOT_R_N")
		)
	)
	(footprint ""
		(layer "B.Cu")
		(at 77.142594 -45.028866)
		(property "Reference" "R3571"
			(at 0 0 0)
			(layer "B.SilkS")
			(hide yes)
			(effects
				(font
					(size 1.27 1.27)
				)
				(justify mirror)
			)
		)
		(property "Value" ""
			(at 0 0 0)
			(layer "B.Fab")
			(effects
				(font
					(size 1.27 1.27)
				)
				(justify mirror)
			)
		)
		(duplicate_pad_numbers_are_jumpers no)
		(fp_line
			(start -0.7874 -0.4064)
			(end -0.7874 0.4064)
			(stroke
				(width 0.1524)
				(type default)
			)
			(layer "B.SilkS")
		)
		(fp_line
			(start -0.7874 0.4064)
			(end 0.7874 0.4064)
			(stroke
				(width 0.1524)
				(type default)
			)
			(layer "B.SilkS")
		)
		(fp_line
			(start 0.7874 -0.4064)
			(end -0.7874 -0.4064)
			(stroke
				(width 0.1524)
				(type default)
			)
			(layer "B.SilkS")
		)
		(fp_line
			(start 0.7874 0.4064)
			(end 0.7874 -0.4064)
			(stroke
				(width 0.1524)
				(type default)
			)
			(layer "B.SilkS")
		)
		(fp_line
			(start -0.67945 -0.3048)
			(end -0.67945 0.3048)
			(stroke
				(width 0.1)
				(type default)
			)
			(layer "B.Fab")
		)
		(fp_line
			(start -0.67945 0.3048)
			(end -0.120396 0.3048)
			(stroke
				(width 0.1)
				(type default)
			)
			(layer "B.Fab")
		)
		(fp_line
			(start -0.12065 -0.3048)
			(end -0.67945 -0.3048)
			(stroke
				(width 0.1)
				(type default)
			)
			(layer "B.Fab")
		)
		(fp_line
			(start -0.12065 -0.2794)
			(end -0.12065 -0.3048)
			(stroke
				(width 0.1)
				(type default)
			)
			(layer "B.Fab")
		)
		(fp_line
			(start -0.120396 0.2794)
			(end 0.12065 0.2794)
			(stroke
				(width 0.1)
				(type default)
			)
			(layer "B.Fab")
		)
		(fp_line
			(start -0.120396 0.3048)
			(end -0.120396 0.2794)
			(stroke
				(width 0.1)
				(type default)
			)
			(layer "B.Fab")
		)
		(fp_line
			(start 0.12065 -0.305054)
			(end 0.12065 -0.2794)
			(stroke
				(width 0.1)
				(type default)
			)
			(layer "B.Fab")
		)
		(fp_line
			(start 0.12065 -0.2794)
			(end -0.12065 -0.2794)
			(stroke
				(width 0.1)
				(type default)
			)
			(layer "B.Fab")
		)
		(fp_line
			(start 0.12065 0.2794)
			(end 0.12065 0.3048)
			(stroke
				(width 0.1)
				(type default)
			)
			(layer "B.Fab")
		)
		(fp_line
			(start 0.12065 0.3048)
			(end 0.67945 0.3048)
			(stroke
				(width 0.1)
				(type default)
			)
			(layer "B.Fab")
		)
		(fp_line
			(start 0.67945 -0.305054)
			(end 0.12065 -0.305054)
			(stroke
				(width 0.1)
				(type default)
			)
			(layer "B.Fab")
		)
		(fp_line
			(start 0.67945 0.3048)
			(end 0.67945 -0.305054)
			(stroke
				(width 0.1)
				(type default)
			)
			(layer "B.Fab")
		)
		(pad "1" smd circle
			(at 0.40005 0 180)
			(size 0 0)
			(layers "B.Cu" "B.Mask" "B.Paste")
			(net "P3V3_OCP_V3_2")
		)
		(pad "2" smd circle
			(at -0.40005 0 180)
			(size 0 0)
			(layers "B.Cu" "B.Mask" "B.Paste")
			(net "VSENSE_P12V_INA230_3_INN")
		)
	)
)
